#ISCELL
  pure_quanta quanta_title_block_c *
  *
#ISCELL
  logical_power universal_gnd *
  page180_i10
#ISCELL
  logical_power universal_gnd *
  page180_i2
#ISCELL
  logical_power universal_gnd *
  page180_i5
#CELL
  pure_quanta emmitsburg_rev0p9 *
  page180_i7
#ISCELL
  logical_power universal_gnd *
  page180_i8
#CELL
  pure_quanta emmitsburg_rev0p9 *
  page180_i9
